(kicad_pcb
	(version 20241229)
	(generator "pcbnew")
	(generator_version "9.0")
	(general
		(thickness 1.61)
		(legacy_teardrops no)
	)
	(paper "A3")
	(title_block
		(title "SO-DIMM DDR5 Tester")
		(date "2025-11-26")
		(rev "1.3.0")
		(comment 9 "footprints 118-122 of 627")
	)
	(layers
		(0 "F.Cu" signal)
		(4 "In1.Cu" power)
		(6 "In2.Cu" mixed)
		(8 "In3.Cu" power)
		(10 "In4.Cu" mixed)
		(12 "In5.Cu" power)
		(14 "In6.Cu" mixed)
		(16 "In7.Cu" power)
		(18 "In8.Cu" power)
		(20 "In9.Cu" mixed)
		(22 "In10.Cu" power)
		(2 "B.Cu" signal)
		(9 "F.Adhes" user "F.Adhesive")
		(11 "B.Adhes" user "B.Adhesive")
		(13 "F.Paste" user)
		(15 "B.Paste" user)
		(5 "F.SilkS" user "F.Silkscreen")
		(7 "B.SilkS" user "B.Silkscreen")
		(1 "F.Mask" user)
		(3 "B.Mask" user)
		(17 "Dwgs.User" user "User.Drawings")
		(19 "Cmts.User" user "User.Comments")
		(21 "Eco1.User" user "User.Eco1")
		(23 "Eco2.User" user "User.Eco2")
		(25 "Edge.Cuts" user)
		(27 "Margin" user)
		(31 "F.CrtYd" user "F.Courtyard")
		(29 "B.CrtYd" user "B.Courtyard")
		(35 "F.Fab" user)
		(33 "B.Fab" user)
	)
	(footprint "antmicro-footprints:VQFN-16-1EP_3x3mm_P0.5mm_EP1.1x1.1mm"
		(layer "F.Cu")
		(at 182.387107 184.914 -90)
		(descr "VQFN, 16 Pin (https://ww1.microchip.com/downloads/en/DeviceDoc/16L_VQFN-WFS_3x3mm_4MX_C04-00508a.pdf), generated with kicad-footprint-generator ipc_noLead_generator.py")
		(tags "VQFN NoLead")
		(property "Reference" "U25"
			(at 2.886 -0.012893 180)
			(layer "F.SilkS")
			(effects
				(font
					(size 0.7 0.7)
					(thickness 0.15)
				)
				(justify left bottom)
			)
		)
		(property "Value" "PAC1954T-E_VQFN"
			(at 0 2.797 270)
			(layer "F.Fab")
			(effects
				(font
					(size 0.7 0.7)
					(thickness 0.15)
				)
				(justify left bottom)
			)
		)
		(property "Datasheet" "https://ww1.microchip.com/downloads/aemDocuments/documents/MSLD/ProductDocuments/DataSheets/PAC195X-Family-Data-Sheet-DS20006539.pdf"
			(at 0 0 270)
			(layer "F.Fab")
			(hide yes)
			(effects
				(font
					(size 1.27 1.27)
					(thickness 0.15)
				)
			)
		)
		(property "Author" "Antmicro"
			(at -2.526893 367.301107 0)
			(layer "F.Fab")
			(hide yes)
			(effects
				(font
					(size 1 1)
					(thickness 0.15)
				)
			)
		)
		(property "License" "Apache-2.0"
			(at -2.526893 367.301107 0)
			(layer "F.Fab")
			(hide yes)
			(effects
				(font
					(size 1 1)
					(thickness 0.15)
				)
			)
		)
		(property "MPN" "PAC1954T-E/4MX"
			(at -2.526893 367.301107 0)
			(layer "F.Fab")
			(hide yes)
			(effects
				(font
					(size 1 1)
					(thickness 0.15)
				)
			)
		)
		(property "Manufacturer" "Microchip Technology"
			(at -2.526893 367.301107 0)
			(layer "F.Fab")
			(hide yes)
			(effects
				(font
					(size 1 1)
					(thickness 0.15)
				)
			)
		)
		(property ki_fp_filters "UQFN*1EP*4x4mm*P0.65mm*")
		(sheetname "/Supply/")
		(sheetfile "supply.kicad_sch")
		(attr smd)
		(fp_line
			(start -1.611 1.61)
			(end -1.611 1.134)
			(stroke
				(width 0.15)
				(type solid)
			)
			(layer "F.SilkS")
		)
		(fp_line
			(start -1.135 1.61)
			(end -1.611 1.61)
			(stroke
				(width 0.15)
				(type solid)
			)
			(layer "F.SilkS")
		)
		(fp_line
			(start 1.134 1.61)
			(end 1.61 1.61)
			(stroke
				(width 0.15)
				(type solid)
			)
			(layer "F.SilkS")
		)
		(fp_line
			(start 1.61 1.61)
			(end 1.61 1.134)
			(stroke
				(width 0.15)
				(type solid)
			)
			(layer "F.SilkS")
		)
		(fp_line
			(start -1.135 -1.611)
			(end -1.611 -1.611)
			(stroke
				(width 0.15)
				(type solid)
			)
			(layer "F.SilkS")
		)
		(fp_line
			(start 1.134 -1.611)
			(end 1.61 -1.611)
			(stroke
				(width 0.15)
				(type solid)
			)
			(layer "F.SilkS")
		)
		(fp_line
			(start 1.61 -1.611)
			(end 1.61 -1.135)
			(stroke
				(width 0.15)
				(type solid)
			)
			(layer "F.SilkS")
		)
		(fp_circle
			(center -2.3 -0.75)
			(end -2.25 -0.75)
			(stroke
				(width 0.15)
				(type solid)
			)
			(fill yes)
			(layer "F.SilkS")
		)
		(fp_rect
			(start -2 -2)
			(end 1.999 1.999)
			(stroke
				(width 0.05)
				(type solid)
			)
			(fill no)
			(layer "F.CrtYd")
		)
		(fp_line
			(start -1.5 1.499)
			(end -1.5 -0.75)
			(stroke
				(width 0.15)
				(type solid)
			)
			(layer "F.Fab")
		)
		(fp_line
			(start 1.499 1.499)
			(end -1.5 1.499)
			(stroke
				(width 0.15)
				(type solid)
			)
			(layer "F.Fab")
		)
		(fp_line
			(start -1.5 -0.75)
			(end -0.75 -1.5)
			(stroke
				(width 0.15)
				(type solid)
			)
			(layer "F.Fab")
		)
		(fp_line
			(start -0.75 -1.5)
			(end 1.499 -1.5)
			(stroke
				(width 0.15)
				(type solid)
			)
			(layer "F.Fab")
		)
		(fp_line
			(start 1.499 -1.5)
			(end 1.499 1.499)
			(stroke
				(width 0.15)
				(type solid)
			)
			(layer "F.Fab")
		)
		(fp_circle
			(center -2.3 -0.75)
			(end -2.25 -0.75)
			(stroke
				(width 0.15)
				(type solid)
			)
			(fill yes)
			(layer "F.Fab")
		)
		(pad "" smd roundrect
			(at 0 0 270)
			(size 0.89 0.89)
			(layers "F.Paste")
			(roundrect_rratio 0.25)
		)
		(pad "1" smd roundrect
			(at -1.464 -0.75 270)
			(size 0.775 0.25)
			(layers "F.Cu" "F.Mask" "F.Paste")
			(roundrect_rratio 0.25)
			(net 1 "GND")
			(pinfunction "SLOW/~{ALERT1}")
			(pintype "bidirectional")
		)
		(pad "2" smd roundrect
			(at -1.464 -0.25 270)
			(size 0.775 0.25)
			(layers "F.Cu" "F.Mask" "F.Paste")
			(roundrect_rratio 0.25)
			(net 200 "+3V3")
			(pinfunction "VDD")
			(pintype "power_in")
		)
		(pad "3" smd roundrect
			(at -1.464 0.247 270)
			(size 0.775 0.25)
			(layers "F.Cu" "F.Mask" "F.Paste")
			(roundrect_rratio 0.25)
			(net 1 "GND")
			(pinfunction "GND")
			(pintype "power_in")
		)
		(pad "4" smd roundrect
			(at -1.464 0.747 270)
			(size 0.775 0.25)
			(layers "F.Cu" "F.Mask" "F.Paste")
			(roundrect_rratio 0.25)
			(net 297 "/Supply/PWR_SCL_2")
			(pinfunction "SCL")
			(pintype "input")
		)
		(pad "5" smd roundrect
			(at -0.75 1.461 270)
			(size 0.25 0.775)
			(layers "F.Cu" "F.Mask" "F.Paste")
			(roundrect_rratio 0.25)
			(net 298 "/Supply/PWR_SDA_2")
			(pinfunction "SDA")
			(pintype "bidirectional")
		)
		(pad "6" smd roundrect
			(at -0.25 1.461 270)
			(size 0.25 0.775)
			(layers "F.Cu" "F.Mask" "F.Paste")
			(roundrect_rratio 0.25)
			(net 200 "+3V3")
			(pinfunction "ADDRSEL")
			(pintype "bidirectional")
		)
		(pad "7" smd roundrect
			(at 0.247 1.461 270)
			(size 0.25 0.775)
			(layers "F.Cu" "F.Mask" "F.Paste")
			(roundrect_rratio 0.25)
			(net 237 "/Supply/sp_SEN_-")
			(pinfunction "IN3-")
			(pintype "input")
		)
		(pad "8" smd roundrect
			(at 0.747 1.461 270)
			(size 0.25 0.775)
			(layers "F.Cu" "F.Mask" "F.Paste")
			(roundrect_rratio 0.25)
			(net 232 "/Supply/sp_SEN_+")
			(pinfunction "IN3+")
			(pintype "input")
		)
		(pad "9" smd roundrect
			(at 1.461 0.747 270)
			(size 0.775 0.25)
			(layers "F.Cu" "F.Mask" "F.Paste")
			(roundrect_rratio 0.25)
			(net 145 "/Supply/1V7_SEN_-")
			(pinfunction "IN4-")
			(pintype "input")
		)
		(pad "10" smd roundrect
			(at 1.461 0.247 270)
			(size 0.775 0.25)
			(layers "F.Cu" "F.Mask" "F.Paste")
			(roundrect_rratio 0.25)
			(net 131 "/Supply/1V7_SEN_+")
			(pinfunction "IN4+")
			(pintype "input")
		)
		(pad "11" smd roundrect
			(at 1.461 -0.25 270)
			(size 0.775 0.25)
			(layers "F.Cu" "F.Mask" "F.Paste")
			(roundrect_rratio 0.25)
			(net 86 "/Supply/MGTAVCC_SEN_+")
			(pinfunction "IN1+")
			(pintype "input")
		)
		(pad "12" smd roundrect
			(at 1.461 -0.75 270)
			(size 0.775 0.25)
			(layers "F.Cu" "F.Mask" "F.Paste")
			(roundrect_rratio 0.25)
			(net 143 "/Supply/MGTAVCC_SEN_-")
			(pinfunction "IN1-")
			(pintype "input")
		)
		(pad "13" smd roundrect
			(at 0.747 -1.464 270)
			(size 0.25 0.775)
			(layers "F.Cu" "F.Mask" "F.Paste")
			(roundrect_rratio 0.25)
			(net 244 "/Supply/1V8_SEN_+")
			(pinfunction "IN2+")
			(pintype "input")
		)
		(pad "14" smd roundrect
			(at 0.247 -1.464 270)
			(size 0.25 0.775)
			(layers "F.Cu" "F.Mask" "F.Paste")
			(roundrect_rratio 0.25)
			(net 246 "/Supply/1V8_SEN_-")
			(pinfunction "IN2-")
			(pintype "input")
		)
		(pad "15" smd roundrect
			(at -0.25 -1.464 270)
			(size 0.25 0.775)
			(layers "F.Cu" "F.Mask" "F.Paste")
			(roundrect_rratio 0.25)
			(net 1 "GND")
			(pinfunction "GPIO/~{ALERT2}")
			(pintype "bidirectional")
		)
		(pad "16" smd roundrect
			(at -0.75 -1.464 270)
			(size 0.25 0.775)
			(layers "F.Cu" "F.Mask" "F.Paste")
			(roundrect_rratio 0.25)
			(net 385 "Net-(U25-~{PWRDN})")
			(pinfunction "~{PWRDN}")
			(pintype "input")
		)
		(pad "17" smd rect
			(at 0 0 270)
			(size 1.1 1.1)
			(layers "F.Cu" "F.Mask")
			(net 731 "unconnected-(U25-EP-Pad17)")
			(pinfunction "EP")
			(pintype "no_connect")
		)
	)
	(footprint "antmicro-footprints:MP_NPTH_Drill3mm"
		(layer "F.Cu")
		(at 202.878201 197.551)
		(property "Reference" "MP3"
			(at 0 -1.8 0)
			(layer "F.SilkS")
			(hide yes)
			(effects
				(font
					(size 0.7 0.7)
					(thickness 0.15)
				)
				(justify left bottom)
			)
		)
		(property "Value" "MP_NPTH_Drill3mm"
			(at 0 2.4 0)
			(layer "F.Fab")
			(effects
				(font
					(size 0.7 0.7)
					(thickness 0.15)
				)
				(justify left bottom)
			)
		)
		(property "Author" "Antmicro"
			(at 0 0 0)
			(layer "F.Fab")
			(hide yes)
			(effects
				(font
					(size 1 1)
					(thickness 0.15)
				)
			)
		)
		(property "License" "Apache-2.0"
			(at 0 0 0)
			(layer "F.Fab")
			(hide yes)
			(effects
				(font
					(size 1 1)
					(thickness 0.15)
				)
			)
		)
		(sheetfile "sodimm-ddr5-tester.kicad_sch")
		(attr board_only exclude_from_pos_files exclude_from_bom)
		(pad "" np_thru_hole circle
			(at 0 0)
			(size 3 3)
			(drill 3)
			(layers "*.Cu" "*.Mask")
		)
	)
	(footprint "antmicro-footprints:C_0402_1005Metric"
		(layer "F.Cu")
		(at 96.5 180.65 -90)
		(descr "Capacitor SMD 0402")
		(tags "capacitor SMD 0402")
		(property "Reference" "C121"
			(at 0 -0.699 270)
			(layer "F.SilkS")
			(hide yes)
			(effects
				(font
					(size 0.7 0.7)
					(thickness 0.15)
				)
				(justify left bottom)
			)
		)
		(property "Value" "C_100n_0402"
			(at -1.022927 2.155213 270)
			(layer "F.Fab")
			(effects
				(font
					(size 0.7 0.7)
					(thickness 0.15)
				)
				(justify left bottom)
			)
		)
		(property "Datasheet" "https://www.murata.com/products/productdetail?partno=GRM155R61H104KE14%23"
			(at 0 0 270)
			(layer "F.Fab")
			(hide yes)
			(effects
				(font
					(size 1.27 1.27)
					(thickness 0.15)
				)
			)
		)
		(property "Author" "Antmicro"
			(at -84.15 277.15 0)
			(layer "F.Fab")
			(hide yes)
			(effects
				(font
					(size 1 1)
					(thickness 0.15)
				)
			)
		)
		(property "Dielectric" "X5R"
			(at -84.15 277.15 0)
			(layer "F.Fab")
			(hide yes)
			(effects
				(font
					(size 1 1)
					(thickness 0.15)
				)
			)
		)
		(property "License" "Apache-2.0"
			(at -84.15 277.15 0)
			(layer "F.Fab")
			(hide yes)
			(effects
				(font
					(size 1 1)
					(thickness 0.15)
				)
			)
		)
		(property "MPN" "GRM155R61H104KE14D"
			(at -84.15 277.15 0)
			(layer "F.Fab")
			(hide yes)
			(effects
				(font
					(size 1 1)
					(thickness 0.15)
				)
			)
		)
		(property "Manufacturer" "Murata"
			(at -84.15 277.15 0)
			(layer "F.Fab")
			(hide yes)
			(effects
				(font
					(size 1 1)
					(thickness 0.15)
				)
			)
		)
		(property "Val" "100n"
			(at -84.15 277.15 0)
			(layer "F.Fab")
			(hide yes)
			(effects
				(font
					(size 1 1)
					(thickness 0.15)
				)
			)
		)
		(property "Voltage" "50V"
			(at -84.15 277.15 0)
			(layer "F.Fab")
			(hide yes)
			(effects
				(font
					(size 1 1)
					(thickness 0.15)
				)
			)
		)
		(sheetname "/Debug FTDI/")
		(sheetfile "debug-ftdi.kicad_sch")
		(attr smd)
		(fp_rect
			(start -0.9659 -0.481258)
			(end 0.9649 0.458742)
			(stroke
				(width 0.05)
				(type solid)
			)
			(fill no)
			(layer "F.CrtYd")
		)
		(fp_line
			(start -0.499 0.248)
			(end -0.499 -0.25)
			(stroke
				(width 0.15)
				(type solid)
			)
			(layer "F.Fab")
		)
		(fp_line
			(start 0.499 0.248)
			(end -0.499 0.248)
			(stroke
				(width 0.15)
				(type solid)
			)
			(layer "F.Fab")
		)
		(fp_line
			(start -0.499 -0.25)
			(end 0.499 -0.25)
			(stroke
				(width 0.15)
				(type solid)
			)
			(layer "F.Fab")
		)
		(fp_line
			(start 0.499 -0.25)
			(end 0.499 0.248)
			(stroke
				(width 0.15)
				(type solid)
			)
			(layer "F.Fab")
		)
		(pad "1" smd roundrect
			(at -0.484 0 270)
			(size 0.59 0.64)
			(layers "F.Cu" "F.Mask" "F.Paste")
			(roundrect_rratio 0.25)
			(net 1 "GND")
			(pintype "passive")
		)
		(pad "2" smd roundrect
			(at 0.484 0 270)
			(size 0.59 0.64)
			(layers "F.Cu" "F.Mask" "F.Paste")
			(roundrect_rratio 0.25)
			(net 6 "/Debug FTDI/FTDI_3V3")
			(pintype "passive")
		)
	)
	(footprint "antmicro-footprints:R_0402_1005Metric"
		(layer "F.Cu")
		(at 202.945501 180.9455 90)
		(descr "Resistor SMD 0402")
		(tags "resistor SMD 0402")
		(property "Reference" "R162"
			(at 0.9455 0.304499 90)
			(layer "F.SilkS")
			(effects
				(font
					(size 0.7 0.7)
					(thickness 0.15)
				)
				(justify left bottom)
			)
		)
		(property "Value" "R_0R_0402"
			(at -1.011843 1.772047 90)
			(layer "F.Fab")
			(effects
				(font
					(size 0.7 0.7)
					(thickness 0.15)
				)
				(justify left bottom)
			)
		)
		(property "Datasheet" "https://industrial.panasonic.com/cdbs/www-data/pdf/RDA0000/AOA0000C301.pdf"
			(at 0 0 90)
			(layer "F.Fab")
			(hide yes)
			(effects
				(font
					(size 1.27 1.27)
					(thickness 0.15)
				)
			)
		)
		(property "Author" "Antmicro"
			(at 383.891001 -22.000001 0)
			(layer "F.Fab")
			(hide yes)
			(effects
				(font
					(size 1 1)
					(thickness 0.15)
				)
			)
		)
		(property "Current" "1A"
			(at 383.891001 -22.000001 0)
			(layer "F.Fab")
			(hide yes)
			(effects
				(font
					(size 1 1)
					(thickness 0.15)
				)
			)
		)
		(property "License" "Apache-2.0"
			(at 383.891001 -22.000001 0)
			(layer "F.Fab")
			(hide yes)
			(effects
				(font
					(size 1 1)
					(thickness 0.15)
				)
			)
		)
		(property "MPN" "ERJ2GE0R00X"
			(at 383.891001 -22.000001 0)
			(layer "F.Fab")
			(hide yes)
			(effects
				(font
					(size 1 1)
					(thickness 0.15)
				)
			)
		)
		(property "Manufacturer" "Panasonic"
			(at 383.891001 -22.000001 0)
			(layer "F.Fab")
			(hide yes)
			(effects
				(font
					(size 1 1)
					(thickness 0.15)
				)
			)
		)
		(property "Tolerance" ""
			(at 383.891001 -22.000001 0)
			(layer "F.Fab")
			(hide yes)
			(effects
				(font
					(size 1 1)
					(thickness 0.15)
				)
			)
		)
		(property "Val" "0R"
			(at 383.891001 -22.000001 0)
			(layer "F.Fab")
			(hide yes)
			(effects
				(font
					(size 1 1)
					(thickness 0.15)
				)
			)
		)
		(sheetname "/Supply/")
		(sheetfile "supply.kicad_sch")
		(attr smd)
		(fp_rect
			(start -0.93 -0.47)
			(end 0.93 0.47)
			(stroke
				(width 0.05)
				(type solid)
			)
			(fill no)
			(layer "F.CrtYd")
		)
		(fp_rect
			(start -0.5 -0.25)
			(end 0.5 0.25)
			(stroke
				(width 0.15)
				(type solid)
			)
			(fill no)
			(layer "F.Fab")
		)
		(pad "1" smd roundrect
			(at -0.485 0 90)
			(size 0.59 0.64)
			(layers "F.Cu" "F.Mask" "F.Paste")
			(roundrect_rratio 0.25)
			(net 216 "/Supply/FB3")
			(pintype "passive")
		)
		(pad "2" smd roundrect
			(at 0.485 0 90)
			(size 0.59 0.64)
			(layers "F.Cu" "F.Mask" "F.Paste")
			(roundrect_rratio 0.25)
			(net 35 "/Supply/spare_local")
			(pintype "passive")
		)
	)
	(footprint "antmicro-footprints:C_0402_1005Metric"
		(layer "F.Cu")
		(at 86.227001 184.9005 180)
		(descr "Capacitor SMD 0402")
		(tags "capacitor SMD 0402")
		(property "Reference" "C126"
			(at 0 -0.699 180)
			(layer "F.SilkS")
			(hide yes)
			(effects
				(font
					(size 0.7 0.7)
					(thickness 0.15)
				)
				(justify left bottom)
			)
		)
		(property "Value" "C_10u_6.3V_0402"
			(at -1.022927 2.155213 180)
			(layer "F.Fab")
			(effects
				(font
					(size 0.7 0.7)
					(thickness 0.15)
				)
				(justify left bottom)
			)
		)
		(property "Datasheet" "https://www.murata.com/products/productdetail?partno=GRM155R60J106ME15%23"
			(at 0 0 180)
			(layer "F.Fab")
			(hide yes)
			(effects
				(font
					(size 1.27 1.27)
					(thickness 0.15)
				)
			)
		)
		(property "Author" "Antmicro"
			(at 172.454002 369.801 0)
			(layer "F.Fab")
			(hide yes)
			(effects
				(font
					(size 1 1)
					(thickness 0.15)
				)
			)
		)
		(property "Dielectric" "X5R"
			(at 172.454002 369.801 0)
			(layer "F.Fab")
			(hide yes)
			(effects
				(font
					(size 1 1)
					(thickness 0.15)
				)
			)
		)
		(property "License" "Apache-2.0"
			(at 172.454002 369.801 0)
			(layer "F.Fab")
			(hide yes)
			(effects
				(font
					(size 1 1)
					(thickness 0.15)
				)
			)
		)
		(property "MPN" "GRM155R60J106ME15D"
			(at 172.454002 369.801 0)
			(layer "F.Fab")
			(hide yes)
			(effects
				(font
					(size 1 1)
					(thickness 0.15)
				)
			)
		)
		(property "Manufacturer" "Murata"
			(at 172.454002 369.801 0)
			(layer "F.Fab")
			(hide yes)
			(effects
				(font
					(size 1 1)
					(thickness 0.15)
				)
			)
		)
		(property "Val" "10u"
			(at 172.454002 369.801 0)
			(layer "F.Fab")
			(hide yes)
			(effects
				(font
					(size 1 1)
					(thickness 0.15)
				)
			)
		)
		(property "Voltage" "6.3V"
			(at 172.454002 369.801 0)
			(layer "F.Fab")
			(hide yes)
			(effects
				(font
					(size 1 1)
					(thickness 0.15)
				)
			)
		)
		(sheetname "/HDMI + SD Card/")
		(sheetfile "hdmi-sd-card.kicad_sch")
		(attr smd)
		(fp_rect
			(start -0.9659 -0.481258)
			(end 0.9649 0.458742)
			(stroke
				(width 0.05)
				(type solid)
			)
			(fill no)
			(layer "F.CrtYd")
		)
		(fp_line
			(start 0.499 0.248)
			(end -0.499 0.248)
			(stroke
				(width 0.15)
				(type solid)
			)
			(layer "F.Fab")
		)
		(fp_line
			(start 0.499 -0.25)
			(end 0.499 0.248)
			(stroke
				(width 0.15)
				(type solid)
			)
			(layer "F.Fab")
		)
		(fp_line
			(start -0.499 0.248)
			(end -0.499 -0.25)
			(stroke
				(width 0.15)
				(type solid)
			)
			(layer "F.Fab")
		)
		(fp_line
			(start -0.499 -0.25)
			(end 0.499 -0.25)
			(stroke
				(width 0.15)
				(type solid)
			)
			(layer "F.Fab")
		)
		(pad "1" smd roundrect
			(at -0.484 0 180)
			(size 0.59 0.64)
			(layers "F.Cu" "F.Mask" "F.Paste")
			(roundrect_rratio 0.25)
			(net 1 "GND")
			(pintype "passive")
		)
		(pad "2" smd roundrect
			(at 0.484 0 180)
			(size 0.59 0.64)
			(layers "F.Cu" "F.Mask" "F.Paste")
			(roundrect_rratio 0.25)
			(net 9 "/HDMI + SD Card/HDMI_CONN_5V")
			(pintype "passive")
		)
	)
)
